(kicad_pcb
	(version 20260206)
	(generator "pcbnew")
	(generator_version "10.0")
	(general
		(thickness 1.6)
		(legacy_teardrops no)
	)
	(paper "A4")
	(title_block
		(title "v1-pdb — T6M_PDB_D_0927_0900.brd")
		(comment 1 "Open CloudServer (Microsoft) / footprints 198-201 of 321")
	)
	(layers
		(0 "F.Cu" signal "TOP")
		(4 "In1.Cu" signal "GND")
		(6 "In2.Cu" signal "IN1")
		(8 "In3.Cu" signal "VCC")
		(10 "In4.Cu" signal "VCC1")
		(12 "In5.Cu" signal "IN2")
		(14 "In6.Cu" signal "GND1")
		(2 "B.Cu" signal "BOTTOM")
		(9 "F.Adhes" user "F.Adhesive")
		(11 "B.Adhes" user "B.Adhesive")
		(13 "F.Paste" user "Package Geometry/Pastemask Top")
		(15 "B.Paste" user "Package Geometry/Pastemask Bottom")
		(5 "F.SilkS" user "Ref Des/Silkscreen Top")
		(7 "B.SilkS" user "Ref Des/Silkscreen Bottom")
		(1 "F.Mask" user "Board Geometry/Soldermask Top")
		(3 "B.Mask" user "Board Geometry/Soldermask Bottom")
		(17 "Dwgs.User" user "User.Drawings")
		(19 "Cmts.User" user "User.Comments")
		(21 "Eco1.User" user "User.Eco1")
		(23 "Eco2.User" user "User.Eco2")
		(25 "Edge.Cuts" user "Board Geometry/Outline")
		(27 "Margin" user)
		(31 "F.CrtYd" user "Package Geometry/Place Bound Top")
		(29 "B.CrtYd" user "Package Geometry/Place Bound Bottom")
		(35 "F.Fab" user "Ref Des/Assembly Top")
		(33 "B.Fab" user "Ref Des/Assembly Bottom")
	)
	(footprint ""
		(layer "F.Cu")
		(at 16.348964 -336.728562)
		(property "Reference" "U1"
			(at 3.592322 0.869696 90)
			(unlocked yes)
			(layer "F.SilkS")
			(effects
				(font
					(size 0.7874 0.5842)
					(thickness 0.1524)
				)
				(justify left)
			)
		)
		(property "Value" ""
			(at 0 0 0)
			(layer "F.Fab")
			(effects
				(font
					(size 1.27 1.27)
				)
			)
		)
		(duplicate_pad_numbers_are_jumpers no)
		(fp_line
			(start -2.5146 -1.4224)
			(end 2.5146 -1.4224)
			(stroke
				(width 0.1524)
				(type default)
			)
			(layer "F.SilkS")
		)
		(fp_line
			(start -2.5146 -0.4572)
			(end -2.5146 -1.4224)
			(stroke
				(width 0.1524)
				(type default)
			)
			(layer "F.SilkS")
		)
		(fp_line
			(start -2.5146 0.4572)
			(end -2.0574 0)
			(stroke
				(width 0.1524)
				(type default)
			)
			(layer "F.SilkS")
		)
		(fp_line
			(start -2.5146 1.4224)
			(end -2.5146 0.4572)
			(stroke
				(width 0.1524)
				(type default)
			)
			(layer "F.SilkS")
		)
		(fp_line
			(start -2.0574 0)
			(end -2.5146 -0.4572)
			(stroke
				(width 0.1524)
				(type default)
			)
			(layer "F.SilkS")
		)
		(fp_line
			(start 2.5146 -1.4224)
			(end 2.5146 1.4224)
			(stroke
				(width 0.1524)
				(type default)
			)
			(layer "F.SilkS")
		)
		(fp_line
			(start 2.5146 1.4224)
			(end -2.5146 1.4224)
			(stroke
				(width 0.1524)
				(type default)
			)
			(layer "F.SilkS")
		)
		(fp_circle
			(center -1.905 0.889)
			(end -1.651 0.889)
			(stroke
				(width 0.1524)
				(type default)
			)
			(fill no)
			(layer "F.SilkS")
		)
		(fp_poly
			(pts
				(xy -2.1844 3.5052) (xy -2.1844 2.0066) (xy -2.5146 2.0066) (xy -2.5146 -2.0066) (xy -2.1844 -2.0066)
				(xy -2.1844 -3.5052) (xy 2.1844 -3.5052) (xy 2.1844 -2.0066) (xy 2.5146 -2.0066) (xy 2.5146 2.0066)
				(xy 2.1844 2.0066) (xy 2.1844 3.5052)
			)
			(stroke
				(width 0)
				(type default)
			)
			(fill no)
			(layer "F.CrtYd")
		)
		(pad "1" smd rect
			(at -1.905 2.6416)
			(size 0.5588 1.7272)
			(layers "F.Cu" "F.Mask" "F.Paste")
			(net "FRU_A0")
		)
		(pad "2" smd rect
			(at -0.635 2.6416)
			(size 0.5588 1.7272)
			(layers "F.Cu" "F.Mask" "F.Paste")
			(net "FRU_A1")
		)
		(pad "3" smd rect
			(at 0.635 2.6416)
			(size 0.5588 1.7272)
			(layers "F.Cu" "F.Mask" "F.Paste")
			(net "FRU_A2")
		)
		(pad "4" smd rect
			(at 1.905 2.6416)
			(size 0.5588 1.7272)
			(layers "F.Cu" "F.Mask" "F.Paste")
			(net "GND")
		)
		(pad "5" smd rect
			(at 1.905 -2.6416)
			(size 0.5588 1.7272)
			(layers "F.Cu" "F.Mask" "F.Paste")
			(net "I2C_PDB_SDA")
		)
		(pad "6" smd rect
			(at 0.635 -2.6416)
			(size 0.5588 1.7272)
			(layers "F.Cu" "F.Mask" "F.Paste")
			(net "I2C_PDB_SCL")
		)
		(pad "7" smd rect
			(at -0.635 -2.6416)
			(size 0.5588 1.7272)
			(layers "F.Cu" "F.Mask" "F.Paste")
			(net "FRU_WP")
		)
		(pad "8" smd rect
			(at -1.905 -2.6416)
			(size 0.5588 1.7272)
			(layers "F.Cu" "F.Mask" "F.Paste")
			(net "P3V3")
		)
	)
	(footprint ""
		(layer "F.Cu")
		(at 26.102056 -277.377144)
		(property "Reference" "R56"
			(at -4.060444 0.200152 0)
			(unlocked yes)
			(layer "F.SilkS")
			(effects
				(font
					(size 0.7874 0.5842)
					(thickness 0.1524)
				)
				(justify left)
			)
		)
		(property "Value" ""
			(at 0 0 0)
			(layer "F.Fab")
			(effects
				(font
					(size 1.27 1.27)
				)
			)
		)
		(duplicate_pad_numbers_are_jumpers no)
		(fp_line
			(start -0.7874 -0.4064)
			(end 0.7874 -0.4064)
			(stroke
				(width 0.1524)
				(type default)
			)
			(layer "F.SilkS")
		)
		(fp_line
			(start -0.7874 0.4064)
			(end -0.7874 -0.4064)
			(stroke
				(width 0.1524)
				(type default)
			)
			(layer "F.SilkS")
		)
		(fp_line
			(start 0.7874 -0.4064)
			(end 0.7874 0.4064)
			(stroke
				(width 0.1524)
				(type default)
			)
			(layer "F.SilkS")
		)
		(fp_line
			(start 0.7874 0.4064)
			(end -0.7874 0.4064)
			(stroke
				(width 0.1524)
				(type default)
			)
			(layer "F.SilkS")
		)
		(fp_poly
			(pts
				(xy -0.508 0.2794) (xy -0.508 0.2286) (xy -0.635 0.2286) (xy -0.635 -0.254) (xy -0.5334 -0.254)
				(xy -0.5334 -0.2794) (xy 0.5334 -0.2794) (xy 0.5334 -0.254) (xy 0.635 -0.254) (xy 0.635 0.254) (xy 0.5334 0.254)
				(xy 0.5334 0.2794)
			)
			(stroke
				(width 0)
				(type default)
			)
			(fill no)
			(layer "F.CrtYd")
		)
		(pad "1" smd rect
			(at 0.40005 0)
			(size 0.4572 0.508)
			(layers "F.Cu" "F.Mask" "F.Paste")
			(net "PSU4_PS_KILL")
		)
		(pad "2" smd rect
			(at -0.40005 0)
			(size 0.4572 0.508)
			(layers "F.Cu" "F.Mask" "F.Paste")
			(net "GND")
		)
	)
	(footprint ""
		(layer "F.Cu")
		(at 73.45934 -326.522588 -90)
		(property "Reference" "C51"
			(at -2.752344 0.042418 90)
			(unlocked yes)
			(layer "F.SilkS")
			(effects
				(font
					(size 0.7874 0.5842)
					(thickness 0.1524)
				)
				(justify left)
			)
		)
		(property "Value" ""
			(at 0 0 270)
			(layer "F.Fab")
			(effects
				(font
					(size 1.27 1.27)
				)
			)
		)
		(duplicate_pad_numbers_are_jumpers no)
		(fp_line
			(start -0.7874 0.4064)
			(end -0.7874 -0.4064)
			(stroke
				(width 0.1524)
				(type default)
			)
			(layer "F.SilkS")
		)
		(fp_line
			(start 0.7874 0.4064)
			(end -0.7874 0.4064)
			(stroke
				(width 0.1524)
				(type default)
			)
			(layer "F.SilkS")
		)
		(fp_line
			(start 0 0.381)
			(end 0 -0.381)
			(stroke
				(width 0.1524)
				(type default)
			)
			(layer "F.SilkS")
		)
		(fp_line
			(start -0.7874 -0.4064)
			(end 0.7874 -0.4064)
			(stroke
				(width 0.1524)
				(type default)
			)
			(layer "F.SilkS")
		)
		(fp_line
			(start 0.7874 -0.4064)
			(end 0.7874 0.4064)
			(stroke
				(width 0.1524)
				(type default)
			)
			(layer "F.SilkS")
		)
		(fp_poly
			(pts
				(xy -0.5334 0.254) (xy -0.635 0.254) (xy -0.635 0.2286) (xy -0.635 -0.254) (xy -0.5334 -0.254) (xy -0.5334 -0.2794)
				(xy 0.5334 -0.2794) (xy 0.5334 -0.254) (xy 0.635 -0.254) (xy 0.635 0.254) (xy 0.5334 0.254) (xy 0.5334 0.2794)
				(xy -0.508 0.2794) (xy -0.5334 0.2794)
			)
			(stroke
				(width 0)
				(type default)
			)
			(fill no)
			(layer "F.CrtYd")
		)
		(pad "1" smd rect
			(at 0.40005 0 270)
			(size 0.4572 0.508)
			(layers "F.Cu" "F.Mask" "F.Paste")
			(net "P12V")
		)
		(pad "2" smd rect
			(at -0.40005 0 270)
			(size 0.4572 0.508)
			(layers "F.Cu" "F.Mask" "F.Paste")
			(net "GND")
		)
	)
	(footprint ""
		(layer "F.Cu")
		(at 39.94531 -459.16596 180)
		(property "Reference" "R26"
			(at -1.790446 -0.167386 0)
			(unlocked yes)
			(layer "F.SilkS")
			(effects
				(font
					(size 0.7874 0.5842)
					(thickness 0.1524)
				)
				(justify left)
			)
		)
		(property "Value" ""
			(at 0 0 180)
			(layer "F.Fab")
			(effects
				(font
					(size 1.27 1.27)
				)
			)
		)
		(duplicate_pad_numbers_are_jumpers no)
		(fp_line
			(start 0.7874 0.4064)
			(end -0.7874 0.4064)
			(stroke
				(width 0.1524)
				(type default)
			)
			(layer "F.SilkS")
		)
		(fp_line
			(start 0.7874 -0.4064)
			(end 0.7874 0.4064)
			(stroke
				(width 0.1524)
				(type default)
			)
			(layer "F.SilkS")
		)
		(fp_line
			(start -0.7874 0.4064)
			(end -0.7874 -0.4064)
			(stroke
				(width 0.1524)
				(type default)
			)
			(layer "F.SilkS")
		)
		(fp_line
			(start -0.7874 -0.4064)
			(end 0.7874 -0.4064)
			(stroke
				(width 0.1524)
				(type default)
			)
			(layer "F.SilkS")
		)
		(fp_poly
			(pts
				(xy -0.508 0.2794) (xy -0.508 0.2286) (xy -0.635 0.2286) (xy -0.635 -0.254) (xy -0.5334 -0.254)
				(xy -0.5334 -0.2794) (xy 0.5334 -0.2794) (xy 0.5334 -0.254) (xy 0.635 -0.254) (xy 0.635 0.254) (xy 0.5334 0.254)
				(xy 0.5334 0.2794)
			)
			(stroke
				(width 0)
				(type default)
			)
			(fill no)
			(layer "F.CrtYd")
		)
		(pad "1" smd rect
			(at 0.40005 0 180)
			(size 0.4572 0.508)
			(layers "F.Cu" "F.Mask" "F.Paste")
			(net "PSU6_RETURN")
		)
		(pad "2" smd rect
			(at -0.40005 0 180)
			(size 0.4572 0.508)
			(layers "F.Cu" "F.Mask" "F.Paste")
			(net "GND")
		)
	)
)
